# S9S_MB_2U (Grand Teton) — schematic netlist excerpt (pin names and nets, part order shuffled) for the footprints in the layout excerpt that follows; sources: Cadence DE-HDL packaged netlist, KiCad conversion of 03242023_DA0F0TMBIJ0_F0T_Motherboard_J_brd_V01_OCP.brd

R822  Q_RES  1K 1% CHIP  pkg 0402LF  page 130 : A = PVCCD_HV_CPU1 ; B = RST_M_EF_CPU1_FPGA_N
C373  Q_CAP  47UF 4V 20% X6S  pkg C0805  page 75 : A = PVCCIN_CPU0 ; B = GND
C560  Q_CAP  0.1UF 25V 10% X7R  pkg 0402  page 235 : A = PVNN_TERM_CPU1 ; B = GND

(kicad_pcb
	(version 20260206)
	(generator "pcbnew")
	(generator_version "10.0")
	(general
		(thickness 1.6)
		(legacy_teardrops no)
	)
	(paper "A4")
	(title_block
		(title "03242023_DA0F0TMBIJ0_F0T_Motherboard_J_brd_V01_OCP.brd")
		(comment 1 "Grand Teton / footprints 6031-6033 of 6105")
	)
	(layers
		(0 "F.Cu" signal "TOP")
		(4 "In1.Cu" signal "GND")
		(6 "In2.Cu" signal "IN1")
		(8 "In3.Cu" signal "GND1")
		(10 "In4.Cu" signal "IN2")
		(12 "In5.Cu" signal "GND2")
		(14 "In6.Cu" signal "IN3")
		(16 "In7.Cu" signal "GND3")
		(18 "In8.Cu" signal "VCC")
		(20 "In9.Cu" signal "VCC1")
		(22 "In10.Cu" signal "GND4")
		(24 "In11.Cu" signal "IN4")
		(26 "In12.Cu" signal "GND5")
		(28 "In13.Cu" signal "IN5")
		(30 "In14.Cu" signal "GND6")
		(32 "In15.Cu" signal "IN6")
		(34 "In16.Cu" signal "GND7")
		(2 "B.Cu" signal "BOTTOM")
		(9 "F.Adhes" user "F.Adhesive")
		(11 "B.Adhes" user "B.Adhesive")
		(13 "F.Paste" user "Package Geometry/Pastemask Top")
		(15 "B.Paste" user "Package Geometry/Pastemask Bottom")
		(5 "F.SilkS" user "Ref Des/Silkscreen Top")
		(7 "B.SilkS" user "Ref Des/Silkscreen Bottom")
		(1 "F.Mask" user "Board Geometry/Soldermask Top")
		(3 "B.Mask" user "Board Geometry/Soldermask Bottom")
		(17 "Dwgs.User" user "User.Drawings")
		(19 "Cmts.User" user "User.Comments")
		(21 "Eco1.User" user "User.Eco1")
		(23 "Eco2.User" user "User.Eco2")
		(25 "Edge.Cuts" user "Board Geometry/Outline")
		(27 "Margin" user)
		(31 "F.CrtYd" user "Package Geometry/Place Bound Top")
		(29 "B.CrtYd" user "Package Geometry/Place Bound Bottom")
		(35 "F.Fab" user "Ref Des/Assembly Top")
		(33 "B.Fab" user "Ref Des/Assembly Bottom")
	)
	(footprint ""
		(layer "B.Cu")
		(at 364.342934 -248.498106 -90)
		(property "Reference" "C373"
			(at 0 0 90)
			(layer "B.SilkS")
			(hide yes)
			(effects
				(font
					(size 1.27 1.27)
				)
				(justify mirror)
			)
		)
		(property "Value" ""
			(at 0 0 90)
			(layer "B.Fab")
			(effects
				(font
					(size 1.27 1.27)
				)
				(justify mirror)
			)
		)
		(duplicate_pad_numbers_are_jumpers no)
		(fp_line
			(start -1.524 0.762)
			(end 1.524 0.762)
			(stroke
				(width 0.1524)
				(type default)
			)
			(layer "B.SilkS")
		)
		(fp_line
			(start 1.524 0.762)
			(end 1.524 -0.762)
			(stroke
				(width 0.1524)
				(type default)
			)
			(layer "B.SilkS")
		)
		(fp_line
			(start -1.524 -0.762)
			(end -1.524 0.762)
			(stroke
				(width 0.1524)
				(type default)
			)
			(layer "B.SilkS")
		)
		(fp_line
			(start 1.524 -0.762)
			(end -1.524 -0.762)
			(stroke
				(width 0.1524)
				(type default)
			)
			(layer "B.SilkS")
		)
		(fp_line
			(start -1.1049 0.724916)
			(end -1.1049 -0.724916)
			(stroke
				(width 0.1)
				(type default)
			)
			(layer "B.Fab")
		)
		(fp_line
			(start 1.1049 0.724916)
			(end -1.1049 0.724916)
			(stroke
				(width 0.1)
				(type default)
			)
			(layer "B.Fab")
		)
		(fp_line
			(start -1.1049 -0.724916)
			(end 1.1049 -0.724916)
			(stroke
				(width 0.1)
				(type default)
			)
			(layer "B.Fab")
		)
		(fp_line
			(start 1.1049 -0.724916)
			(end 1.1049 0.724916)
			(stroke
				(width 0.1)
				(type default)
			)
			(layer "B.Fab")
		)
		(pad "1" smd rect
			(at 0.889 0 270)
			(size 1.016 1.27)
			(layers "B.Cu" "B.Mask" "B.Paste")
			(net "PVCCIN_CPU0")
		)
		(pad "2" smd rect
			(at -0.889 0 270)
			(size 1.016 1.27)
			(layers "B.Cu" "B.Mask" "B.Paste")
			(net "GND")
		)
	)
	(footprint ""
		(layer "B.Cu")
		(at 185.142886 -193.599816 -90)
		(property "Reference" "R822"
			(at 0 0 90)
			(layer "B.SilkS")
			(hide yes)
			(effects
				(font
					(size 1.27 1.27)
				)
				(justify mirror)
			)
		)
		(property "Value" ""
			(at 0 0 90)
			(layer "B.Fab")
			(effects
				(font
					(size 1.27 1.27)
				)
				(justify mirror)
			)
		)
		(duplicate_pad_numbers_are_jumpers no)
		(fp_line
			(start -0.7874 0.4064)
			(end 0.7874 0.4064)
			(stroke
				(width 0.1524)
				(type default)
			)
			(layer "B.SilkS")
		)
		(fp_line
			(start 0.7874 0.4064)
			(end 0.7874 -0.4064)
			(stroke
				(width 0.1524)
				(type default)
			)
			(layer "B.SilkS")
		)
		(fp_line
			(start -0.7874 -0.4064)
			(end -0.7874 0.4064)
			(stroke
				(width 0.1524)
				(type default)
			)
			(layer "B.SilkS")
		)
		(fp_line
			(start 0.7874 -0.4064)
			(end -0.7874 -0.4064)
			(stroke
				(width 0.1524)
				(type default)
			)
			(layer "B.SilkS")
		)
		(fp_line
			(start -0.67945 0.3048)
			(end -0.120396 0.3048)
			(stroke
				(width 0.1)
				(type default)
			)
			(layer "B.Fab")
		)
		(fp_line
			(start -0.120396 0.3048)
			(end -0.120396 0.2794)
			(stroke
				(width 0.1)
				(type default)
			)
			(layer "B.Fab")
		)
		(fp_line
			(start 0.12065 0.3048)
			(end 0.67945 0.3048)
			(stroke
				(width 0.1)
				(type default)
			)
			(layer "B.Fab")
		)
		(fp_line
			(start 0.67945 0.3048)
			(end 0.67945 -0.305054)
			(stroke
				(width 0.1)
				(type default)
			)
			(layer "B.Fab")
		)
		(fp_line
			(start -0.120396 0.2794)
			(end 0.12065 0.2794)
			(stroke
				(width 0.1)
				(type default)
			)
			(layer "B.Fab")
		)
		(fp_line
			(start 0.12065 0.2794)
			(end 0.12065 0.3048)
			(stroke
				(width 0.1)
				(type default)
			)
			(layer "B.Fab")
		)
		(fp_line
			(start -0.12065 -0.2794)
			(end -0.12065 -0.3048)
			(stroke
				(width 0.1)
				(type default)
			)
			(layer "B.Fab")
		)
		(fp_line
			(start 0.12065 -0.2794)
			(end -0.12065 -0.2794)
			(stroke
				(width 0.1)
				(type default)
			)
			(layer "B.Fab")
		)
		(fp_line
			(start -0.67945 -0.3048)
			(end -0.67945 0.3048)
			(stroke
				(width 0.1)
				(type default)
			)
			(layer "B.Fab")
		)
		(fp_line
			(start -0.12065 -0.3048)
			(end -0.67945 -0.3048)
			(stroke
				(width 0.1)
				(type default)
			)
			(layer "B.Fab")
		)
		(fp_line
			(start 0.12065 -0.305054)
			(end 0.12065 -0.2794)
			(stroke
				(width 0.1)
				(type default)
			)
			(layer "B.Fab")
		)
		(fp_line
			(start 0.67945 -0.305054)
			(end 0.12065 -0.305054)
			(stroke
				(width 0.1)
				(type default)
			)
			(layer "B.Fab")
		)
		(pad "1" smd circle
			(at 0.40005 0 90)
			(size 0 0)
			(layers "B.Cu" "B.Mask" "B.Paste")
			(net "PVCCD_HV_CPU1")
		)
		(pad "2" smd circle
			(at -0.40005 0 90)
			(size 0 0)
			(layers "B.Cu" "B.Mask" "B.Paste")
			(net "RST_M_EF_CPU1_FPGA_N")
		)
	)
	(footprint ""
		(layer "B.Cu")
		(at 17.75206 -193.843656 180)
		(property "Reference" "C560"
			(at 0 0 0)
			(layer "B.SilkS")
			(hide yes)
			(effects
				(font
					(size 1.27 1.27)
				)
				(justify mirror)
			)
		)
		(property "Value" ""
			(at 0 0 0)
			(layer "B.Fab")
			(effects
				(font
					(size 1.27 1.27)
				)
				(justify mirror)
			)
		)
		(duplicate_pad_numbers_are_jumpers no)
		(fp_line
			(start 0.7874 0.4064)
			(end 0.7874 -0.4064)
			(stroke
				(width 0.1524)
				(type default)
			)
			(layer "B.SilkS")
		)
		(fp_line
			(start 0.7874 -0.4064)
			(end -0.7874 -0.4064)
			(stroke
				(width 0.1524)
				(type default)
			)
			(layer "B.SilkS")
		)
		(fp_line
			(start -0.7874 0.4064)
			(end 0.7874 0.4064)
			(stroke
				(width 0.1524)
				(type default)
			)
			(layer "B.SilkS")
		)
		(fp_line
			(start -0.7874 -0.4064)
			(end -0.7874 0.4064)
			(stroke
				(width 0.1524)
				(type default)
			)
			(layer "B.SilkS")
		)
		(fp_line
			(start 0.67945 0.3048)
			(end 0.67945 -0.305054)
			(stroke
				(width 0.1)
				(type default)
			)
			(layer "B.Fab")
		)
		(fp_line
			(start 0.67945 -0.305054)
			(end 0.12065 -0.305054)
			(stroke
				(width 0.1)
				(type default)
			)
			(layer "B.Fab")
		)
		(fp_line
			(start 0.12065 0.3048)
			(end 0.67945 0.3048)
			(stroke
				(width 0.1)
				(type default)
			)
			(layer "B.Fab")
		)
		(fp_line
			(start 0.12065 0.2794)
			(end 0.12065 0.3048)
			(stroke
				(width 0.1)
				(type default)
			)
			(layer "B.Fab")
		)
		(fp_line
			(start 0.12065 -0.2794)
			(end -0.12065 -0.2794)
			(stroke
				(width 0.1)
				(type default)
			)
			(layer "B.Fab")
		)
		(fp_line
			(start 0.12065 -0.305054)
			(end 0.12065 -0.2794)
			(stroke
				(width 0.1)
				(type default)
			)
			(layer "B.Fab")
		)
		(fp_line
			(start -0.120396 0.3048)
			(end -0.120396 0.2794)
			(stroke
				(width 0.1)
				(type default)
			)
			(layer "B.Fab")
		)
		(fp_line
			(start -0.120396 0.2794)
			(end 0.12065 0.2794)
			(stroke
				(width 0.1)
				(type default)
			)
			(layer "B.Fab")
		)
		(fp_line
			(start -0.12065 -0.2794)
			(end -0.12065 -0.3048)
			(stroke
				(width 0.1)
				(type default)
			)
			(layer "B.Fab")
		)
		(fp_line
			(start -0.12065 -0.3048)
			(end -0.67945 -0.3048)
			(stroke
				(width 0.1)
				(type default)
			)
			(layer "B.Fab")
		)
		(fp_line
			(start -0.67945 0.3048)
			(end -0.120396 0.3048)
			(stroke
				(width 0.1)
				(type default)
			)
			(layer "B.Fab")
		)
		(fp_line
			(start -0.67945 -0.3048)
			(end -0.67945 0.3048)
			(stroke
				(width 0.1)
				(type default)
			)
			(layer "B.Fab")
		)
		(pad "1" smd circle
			(at 0.40005 0)
			(size 0 0)
			(layers "B.Cu" "B.Mask" "B.Paste")
			(net "PVNN_TERM_CPU1")
		)
		(pad "2" smd circle
			(at -0.40005 0)
			(size 0 0)
			(layers "B.Cu" "B.Mask" "B.Paste")
			(net "GND")
		)
	)
)
